(kicad_pcb
	(version 20260206)
	(generator "pcbnew")
	(generator_version "10.0")
	(general
		(thickness 1.6)
		(legacy_teardrops no)
	)
	(paper "A4")
	(title_block
		(title "dpb — 14545-sa.0730WZS0815.brd")
		(comment 1 "Honey Badger (Wiwynn) / footprints 984-990 of 1066")
	)
	(layers
		(0 "F.Cu" signal "TOP")
		(4 "In1.Cu" signal "L2GND")
		(6 "In2.Cu" signal "L3")
		(8 "In3.Cu" signal "L4VCC")
		(10 "In4.Cu" signal "L5VCC")
		(12 "In5.Cu" signal "L6")
		(14 "In6.Cu" signal "L7GND")
		(2 "B.Cu" signal "BOTTOM")
		(9 "F.Adhes" user "F.Adhesive")
		(11 "B.Adhes" user "B.Adhesive")
		(13 "F.Paste" user "Package Geometry/Pastemask Top")
		(15 "B.Paste" user "Package Geometry/Pastemask Bottom")
		(5 "F.SilkS" user "Ref Des/Silkscreen Top")
		(7 "B.SilkS" user "Ref Des/Silkscreen Bottom")
		(1 "F.Mask" user "Board Geometry/Soldermask Top")
		(3 "B.Mask" user "Board Geometry/Soldermask Bottom")
		(17 "Dwgs.User" user "User.Drawings")
		(19 "Cmts.User" user "User.Comments")
		(21 "Eco1.User" user "User.Eco1")
		(23 "Eco2.User" user "User.Eco2")
		(25 "Edge.Cuts" user "Board Geometry/Outline")
		(27 "Margin" user)
		(31 "F.CrtYd" user "Package Geometry/Place Bound Top")
		(29 "B.CrtYd" user "Package Geometry/Place Bound Bottom")
		(35 "F.Fab" user "Ref Des/Assembly Top")
		(33 "B.Fab" user "Ref Des/Assembly Bottom")
	)
	(footprint ""
		(layer "F.Cu")
		(at 97.789746 -6.6167 90)
		(property "Reference" "R307"
			(at 0 0 90)
			(layer "F.SilkS")
			(hide yes)
			(effects
				(font
					(size 1.27 1.27)
				)
			)
		)
		(property "Value" "200KR2F-L-GP"
			(at 0.064008 -3.993896 90)
			(unlocked yes)
			(layer "F.Fab")
			(hide yes)
			(effects
				(font
					(size 1.016 1.016)
					(thickness 0.1524)
				)
			)
		)
		(property "Device Type" "R402H16"
			(at 0.064008 -5.517896 90)
			(unlocked yes)
			(layer "F.Fab")
			(hide yes)
			(effects
				(font
					(size 1.016 1.016)
					(thickness 0.1524)
				)
			)
		)
		(duplicate_pad_numbers_are_jumpers no)
		(fp_line
			(start 0.508 -0.9398)
			(end -0.508 -0.9398)
			(stroke
				(width 0.1524)
				(type default)
			)
			(layer "F.SilkS")
		)
		(fp_line
			(start -0.508 -0.9398)
			(end -0.508 0.9398)
			(stroke
				(width 0.1524)
				(type default)
			)
			(layer "F.SilkS")
		)
		(fp_rect
			(start -0.508 0.9398)
			(end 0.508 -0.9398)
			(stroke
				(width 0)
				(type default)
			)
			(fill no)
			(layer "F.CrtYd")
		)
		(fp_rect
			(start -0.508 0.9398)
			(end 0.508 -0.9398)
			(stroke
				(width 0)
				(type default)
			)
			(fill no)
			(layer "F.Fab")
		)
		(pad "1" smd custom
			(at 0 -0.4445 90)
			(size 0.1397 0.1397)
			(layers "F.Cu" "F.Mask" "F.Paste")
			(net "P12V")
			(options
				(clearance outline)
				(anchor circle)
			)
			(primitives
				(gr_poly
					(pts
						(arc
							(start -0.1778 -0.2794)
							(mid -0.249642 -0.249642)
							(end -0.2794 -0.1778)
						)
						(arc
							(start -0.2794 0.1778)
							(mid -0.249642 0.249642)
							(end -0.1778 0.2794)
						)
						(arc
							(start 0.1778 0.2794)
							(mid 0.249642 0.249642)
							(end 0.2794 0.1778)
						)
						(arc
							(start 0.2794 -0.1778)
							(mid 0.249642 -0.249642)
							(end 0.1778 -0.2794)
						)
					)
					(width 0)
					(fill yes)
				)
			)
		)
		(pad "2" smd custom
			(at 0 0.4445 90)
			(size 0.1397 0.1397)
			(layers "F.Cu" "F.Mask" "F.Paste")
			(net "SW_HDD14_P")
			(options
				(clearance outline)
				(anchor circle)
			)
			(primitives
				(gr_poly
					(pts
						(arc
							(start -0.1778 -0.2794)
							(mid -0.249642 -0.249642)
							(end -0.2794 -0.1778)
						)
						(arc
							(start -0.2794 0.1778)
							(mid -0.249642 0.249642)
							(end -0.1778 0.2794)
						)
						(arc
							(start 0.1778 0.2794)
							(mid 0.249642 0.249642)
							(end 0.2794 0.1778)
						)
						(arc
							(start 0.2794 -0.1778)
							(mid 0.249642 -0.249642)
							(end 0.1778 -0.2794)
						)
					)
					(width 0)
					(fill yes)
				)
			)
		)
	)
	(footprint ""
		(layer "F.Cu")
		(at 78.358746 -189.4967 -90)
		(property "Reference" "R225"
			(at 0 0 270)
			(layer "F.SilkS")
			(hide yes)
			(effects
				(font
					(size 1.27 1.27)
				)
			)
		)
		(property "Value" "0R2J-2-GP"
			(at 0.064008 -3.993896 270)
			(unlocked yes)
			(layer "F.Fab")
			(hide yes)
			(effects
				(font
					(size 1.016 1.016)
					(thickness 0.1524)
				)
			)
		)
		(property "Device Type" "R402H16"
			(at 0.064008 -5.517896 270)
			(unlocked yes)
			(layer "F.Fab")
			(hide yes)
			(effects
				(font
					(size 1.016 1.016)
					(thickness 0.1524)
				)
			)
		)
		(duplicate_pad_numbers_are_jumpers no)
		(fp_line
			(start -0.508 -0.9398)
			(end -0.508 0.9398)
			(stroke
				(width 0.1524)
				(type default)
			)
			(layer "F.SilkS")
		)
		(fp_line
			(start 0.508 -0.9398)
			(end -0.508 -0.9398)
			(stroke
				(width 0.1524)
				(type default)
			)
			(layer "F.SilkS")
		)
		(fp_rect
			(start -0.508 0.9398)
			(end 0.508 -0.9398)
			(stroke
				(width 0)
				(type default)
			)
			(fill no)
			(layer "F.CrtYd")
		)
		(fp_rect
			(start -0.508 0.9398)
			(end 0.508 -0.9398)
			(stroke
				(width 0)
				(type default)
			)
			(fill no)
			(layer "F.Fab")
		)
		(pad "1" smd custom
			(at 0 -0.4445 270)
			(size 0.1397 0.1397)
			(layers "F.Cu" "F.Mask" "F.Paste")
			(net "DRIVE_PWR8")
			(options
				(clearance outline)
				(anchor circle)
			)
			(primitives
				(gr_poly
					(pts
						(arc
							(start -0.1778 -0.2794)
							(mid -0.249642 -0.249642)
							(end -0.2794 -0.1778)
						)
						(arc
							(start -0.2794 0.1778)
							(mid -0.249642 0.249642)
							(end -0.1778 0.2794)
						)
						(arc
							(start 0.1778 0.2794)
							(mid 0.249642 0.249642)
							(end 0.2794 0.1778)
						)
						(arc
							(start 0.2794 -0.1778)
							(mid 0.249642 -0.249642)
							(end 0.1778 -0.2794)
						)
					)
					(width 0)
					(fill yes)
				)
			)
		)
		(pad "2" smd custom
			(at 0 0.4445 270)
			(size 0.1397 0.1397)
			(layers "F.Cu" "F.Mask" "F.Paste")
			(net "SW_PWR_HDD8")
			(options
				(clearance outline)
				(anchor circle)
			)
			(primitives
				(gr_poly
					(pts
						(arc
							(start -0.1778 -0.2794)
							(mid -0.249642 -0.249642)
							(end -0.2794 -0.1778)
						)
						(arc
							(start -0.2794 0.1778)
							(mid -0.249642 0.249642)
							(end -0.1778 0.2794)
						)
						(arc
							(start 0.1778 0.2794)
							(mid 0.249642 0.249642)
							(end 0.2794 0.1778)
						)
						(arc
							(start 0.2794 -0.1778)
							(mid 0.249642 -0.249642)
							(end 0.1778 -0.2794)
						)
					)
					(width 0)
					(fill yes)
				)
			)
		)
	)
	(footprint ""
		(layer "F.Cu")
		(at 30.606746 -285.7627 90)
		(property "Reference" "R207"
			(at 0 0 90)
			(layer "F.SilkS")
			(hide yes)
			(effects
				(font
					(size 1.27 1.27)
				)
			)
		)
		(property "Value" "200KR2F-L-GP"
			(at 0.064008 -3.993896 90)
			(unlocked yes)
			(layer "F.Fab")
			(hide yes)
			(effects
				(font
					(size 1.016 1.016)
					(thickness 0.1524)
				)
			)
		)
		(property "Device Type" "R402H16"
			(at 0.064008 -5.517896 90)
			(unlocked yes)
			(layer "F.Fab")
			(hide yes)
			(effects
				(font
					(size 1.016 1.016)
					(thickness 0.1524)
				)
			)
		)
		(duplicate_pad_numbers_are_jumpers no)
		(fp_line
			(start 0.508 -0.9398)
			(end -0.508 -0.9398)
			(stroke
				(width 0.1524)
				(type default)
			)
			(layer "F.SilkS")
		)
		(fp_line
			(start -0.508 -0.9398)
			(end -0.508 0.9398)
			(stroke
				(width 0.1524)
				(type default)
			)
			(layer "F.SilkS")
		)
		(fp_rect
			(start -0.508 0.9398)
			(end 0.508 -0.9398)
			(stroke
				(width 0)
				(type default)
			)
			(fill no)
			(layer "F.CrtYd")
		)
		(fp_rect
			(start -0.508 0.9398)
			(end 0.508 -0.9398)
			(stroke
				(width 0)
				(type default)
			)
			(fill no)
			(layer "F.Fab")
		)
		(pad "1" smd custom
			(at 0 -0.4445 90)
			(size 0.1397 0.1397)
			(layers "F.Cu" "F.Mask" "F.Paste")
			(net "P12V")
			(options
				(clearance outline)
				(anchor circle)
			)
			(primitives
				(gr_poly
					(pts
						(arc
							(start -0.1778 -0.2794)
							(mid -0.249642 -0.249642)
							(end -0.2794 -0.1778)
						)
						(arc
							(start -0.2794 0.1778)
							(mid -0.249642 0.249642)
							(end -0.1778 0.2794)
						)
						(arc
							(start 0.1778 0.2794)
							(mid 0.249642 0.249642)
							(end 0.2794 0.1778)
						)
						(arc
							(start 0.2794 -0.1778)
							(mid 0.249642 -0.249642)
							(end 0.1778 -0.2794)
						)
					)
					(width 0)
					(fill yes)
				)
			)
		)
		(pad "2" smd custom
			(at 0 0.4445 90)
			(size 0.1397 0.1397)
			(layers "F.Cu" "F.Mask" "F.Paste")
			(net "SW_HDD7_P")
			(options
				(clearance outline)
				(anchor circle)
			)
			(primitives
				(gr_poly
					(pts
						(arc
							(start -0.1778 -0.2794)
							(mid -0.249642 -0.249642)
							(end -0.2794 -0.1778)
						)
						(arc
							(start -0.2794 0.1778)
							(mid -0.249642 0.249642)
							(end -0.1778 0.2794)
						)
						(arc
							(start 0.1778 0.2794)
							(mid 0.249642 0.249642)
							(end 0.2794 0.1778)
						)
						(arc
							(start 0.2794 -0.1778)
							(mid 0.249642 -0.249642)
							(end 0.1778 -0.2794)
						)
					)
					(width 0)
					(fill yes)
				)
			)
		)
	)
	(footprint ""
		(layer "F.Cu")
		(at 49.403 -127.254 180)
		(property "Reference" "C309"
			(at 0 0 180)
			(layer "F.SilkS")
			(hide yes)
			(effects
				(font
					(size 1.27 1.27)
				)
			)
		)
		(property "Value" "SCD1U10V2KX-5GP"
			(at 1.1811 -2.7051 180)
			(unlocked yes)
			(layer "F.Fab")
			(hide yes)
			(effects
				(font
					(size 1.016 1.016)
					(thickness 0.1524)
				)
			)
		)
		(property "Device Type" "C402H22"
			(at 1.1811 -4.2291 180)
			(unlocked yes)
			(layer "F.Fab")
			(hide yes)
			(effects
				(font
					(size 1.016 1.016)
					(thickness 0.1524)
				)
			)
		)
		(duplicate_pad_numbers_are_jumpers no)
		(fp_rect
			(start -0.4318 0.9525)
			(end 0.4318 -0.9525)
			(stroke
				(width 0)
				(type default)
			)
			(fill no)
			(layer "F.CrtYd")
		)
		(fp_rect
			(start -0.4318 0.9525)
			(end 0.4318 -0.9525)
			(stroke
				(width 0)
				(type default)
			)
			(fill no)
			(layer "F.Fab")
		)
		(pad "1" smd custom
			(at 0 -0.4445 180)
			(size 0.1524 0.1524)
			(layers "F.Cu" "F.Mask" "F.Paste")
			(net "P3V3")
			(options
				(clearance outline)
				(anchor circle)
			)
			(primitives
				(gr_poly
					(pts
						(arc
							(start 0.3048 -0.2032)
							(mid 0.275042 -0.275042)
							(end 0.2032 -0.3048)
						)
						(arc
							(start -0.2032 -0.3048)
							(mid -0.275042 -0.275042)
							(end -0.3048 -0.2032)
						)
						(arc
							(start -0.3048 0.2032)
							(mid -0.275042 0.275042)
							(end -0.2032 0.3048)
						)
						(arc
							(start 0.2032 0.3048)
							(mid 0.275042 0.275042)
							(end 0.3048 0.2032)
						)
					)
					(width 0)
					(fill yes)
				)
			)
		)
		(pad "2" smd custom
			(at 0 0.4445 180)
			(size 0.1524 0.1524)
			(layers "F.Cu" "F.Mask" "F.Paste")
			(net "GND")
			(options
				(clearance outline)
				(anchor circle)
			)
			(primitives
				(gr_poly
					(pts
						(arc
							(start 0.3048 -0.2032)
							(mid 0.275042 -0.275042)
							(end 0.2032 -0.3048)
						)
						(arc
							(start -0.2032 -0.3048)
							(mid -0.275042 -0.275042)
							(end -0.3048 -0.2032)
						)
						(arc
							(start -0.3048 0.2032)
							(mid -0.275042 0.275042)
							(end -0.2032 0.3048)
						)
						(arc
							(start 0.2032 0.3048)
							(mid 0.275042 0.275042)
							(end 0.3048 0.2032)
						)
					)
					(width 0)
					(fill yes)
				)
			)
		)
	)
	(footprint ""
		(layer "F.Cu")
		(at 81.69656 -498.544088)
		(property "Reference" "Q12"
			(at 0 0 0)
			(layer "F.SilkS")
			(hide yes)
			(effects
				(font
					(size 1.27 1.27)
				)
			)
		)
		(property "Value" "2N7002DW-7F-GP"
			(at -2.3622 -8.2042 0)
			(unlocked yes)
			(layer "F.Fab")
			(hide yes)
			(effects
				(font
					(size 1.016 1.016)
					(thickness 0.1524)
				)
			)
		)
		(property "Device Type" "SOT-363H44"
			(at -2.3622 -10.1092 0)
			(unlocked yes)
			(layer "F.Fab")
			(hide yes)
			(effects
				(font
					(size 1.016 1.016)
					(thickness 0.1524)
				)
			)
		)
		(duplicate_pad_numbers_are_jumpers no)
		(fp_line
			(start -1.4478 -1.7018)
			(end -1.4478 1.7018)
			(stroke
				(width 0.1524)
				(type default)
			)
			(layer "F.SilkS")
		)
		(fp_line
			(start -1.4478 1.7018)
			(end 1.4478 1.7018)
			(stroke
				(width 0.1524)
				(type default)
			)
			(layer "F.SilkS")
		)
		(fp_line
			(start -1.27 1.524)
			(end -1.27 0.6604)
			(stroke
				(width 0.4826)
				(type default)
			)
			(layer "F.SilkS")
		)
		(fp_line
			(start 1.4478 -1.7018)
			(end -1.4478 -1.7018)
			(stroke
				(width 0.1524)
				(type default)
			)
			(layer "F.SilkS")
		)
		(fp_line
			(start 1.4478 1.7018)
			(end 1.4478 -1.7018)
			(stroke
				(width 0.1524)
				(type default)
			)
			(layer "F.SilkS")
		)
		(fp_poly
			(pts
				(xy -1.524 -1.778) (xy 1.524 -1.778) (xy 1.524 1.778) (xy -1.524 1.778)
			)
			(stroke
				(width 0)
				(type default)
			)
			(fill no)
			(layer "F.CrtYd")
		)
		(fp_poly
			(pts
				(xy -1.524 -1.778) (xy 1.524 -1.778) (xy 1.524 1.778) (xy -1.524 1.778)
			)
			(stroke
				(width 0)
				(type default)
			)
			(fill no)
			(layer "F.Fab")
		)
		(pad "1" smd rect
			(at -0.65024 0.9398)
			(size 0.4064 1.016)
			(layers "F.Cu" "F.Mask" "F.Paste")
			(net "GND")
		)
		(pad "2" smd rect
			(at 0 0.9398)
			(size 0.4064 1.016)
			(layers "F.Cu" "F.Mask" "F.Paste")
			(net "SW_PWR_R_HDD5")
		)
		(pad "3" smd rect
			(at 0.65024 0.9398)
			(size 0.4064 1.016)
			(layers "F.Cu" "F.Mask" "F.Paste")
			(net "SW_HDD5_P")
		)
		(pad "4" smd rect
			(at 0.65024 -0.9398)
			(size 0.4064 1.016)
			(layers "F.Cu" "F.Mask" "F.Paste")
			(net "GND")
		)
		(pad "5" smd rect
			(at 0 -0.9398)
			(size 0.4064 1.016)
			(layers "F.Cu" "F.Mask" "F.Paste")
			(net "SW_HDD5_G")
		)
		(pad "6" smd rect
			(at -0.65024 -0.9398)
			(size 0.4064 1.016)
			(layers "F.Cu" "F.Mask" "F.Paste")
			(net "SW_HDD5_R")
		)
	)
	(footprint ""
		(layer "F.Cu")
		(at 209.7278 -273.685)
		(property "Reference" "R363"
			(at 0 0 0)
			(layer "F.SilkS")
			(hide yes)
			(effects
				(font
					(size 1.27 1.27)
				)
			)
		)
		(property "Value" "10KR2F-2-GP"
			(at 0.064008 -3.993896 0)
			(unlocked yes)
			(layer "F.Fab")
			(hide yes)
			(effects
				(font
					(size 1.016 1.016)
					(thickness 0.1524)
				)
			)
		)
		(property "Device Type" "R402H16"
			(at 0.064008 -5.517896 0)
			(unlocked yes)
			(layer "F.Fab")
			(hide yes)
			(effects
				(font
					(size 1.016 1.016)
					(thickness 0.1524)
				)
			)
		)
		(duplicate_pad_numbers_are_jumpers no)
		(fp_line
			(start -0.508 -0.9398)
			(end -0.508 0.9398)
			(stroke
				(width 0.1524)
				(type default)
			)
			(layer "F.SilkS")
		)
		(fp_line
			(start 0.508 -0.9398)
			(end -0.508 -0.9398)
			(stroke
				(width 0.1524)
				(type default)
			)
			(layer "F.SilkS")
		)
		(fp_rect
			(start -0.508 0.9398)
			(end 0.508 -0.9398)
			(stroke
				(width 0)
				(type default)
			)
			(fill no)
			(layer "F.CrtYd")
		)
		(fp_rect
			(start -0.508 0.9398)
			(end 0.508 -0.9398)
			(stroke
				(width 0)
				(type default)
			)
			(fill no)
			(layer "F.Fab")
		)
		(pad "1" smd custom
			(at 0 -0.4445)
			(size 0.1397 0.1397)
			(layers "F.Cu" "F.Mask" "F.Paste")
			(net "P12V")
			(options
				(clearance outline)
				(anchor circle)
			)
			(primitives
				(gr_poly
					(pts
						(arc
							(start -0.1778 -0.2794)
							(mid -0.249642 -0.249642)
							(end -0.2794 -0.1778)
						)
						(arc
							(start -0.2794 0.1778)
							(mid -0.249642 0.249642)
							(end -0.1778 0.2794)
						)
						(arc
							(start 0.1778 0.2794)
							(mid 0.249642 0.249642)
							(end 0.2794 0.1778)
						)
						(arc
							(start 0.2794 -0.1778)
							(mid 0.249642 -0.249642)
							(end 0.1778 -0.2794)
						)
					)
					(width 0)
					(fill yes)
				)
			)
		)
		(pad "2" smd custom
			(at 0 0.4445)
			(size 0.1397 0.1397)
			(layers "F.Cu" "F.Mask" "F.Paste")
			(net "HDD2_LED_G")
			(options
				(clearance outline)
				(anchor circle)
			)
			(primitives
				(gr_poly
					(pts
						(arc
							(start -0.1778 -0.2794)
							(mid -0.249642 -0.249642)
							(end -0.2794 -0.1778)
						)
						(arc
							(start -0.2794 0.1778)
							(mid -0.249642 0.249642)
							(end -0.1778 0.2794)
						)
						(arc
							(start 0.1778 0.2794)
							(mid 0.249642 0.249642)
							(end 0.2794 0.1778)
						)
						(arc
							(start 0.2794 -0.1778)
							(mid 0.249642 -0.249642)
							(end 0.1778 -0.2794)
						)
					)
					(width 0)
					(fill yes)
				)
			)
		)
	)
	(footprint ""
		(layer "F.Cu")
		(at 23.114 -395.605 90)
		(property "Reference" "R511"
			(at 0 0 90)
			(layer "F.SilkS")
			(hide yes)
			(effects
				(font
					(size 1.27 1.27)
				)
			)
		)
		(property "Value" "0R2J-2-GP"
			(at 0.064008 -3.993896 90)
			(unlocked yes)
			(layer "F.Fab")
			(hide yes)
			(effects
				(font
					(size 1.016 1.016)
					(thickness 0.1524)
				)
			)
		)
		(property "Device Type" "R402H16"
			(at 0.064008 -5.517896 90)
			(unlocked yes)
			(layer "F.Fab")
			(hide yes)
			(effects
				(font
					(size 1.016 1.016)
					(thickness 0.1524)
				)
			)
		)
		(duplicate_pad_numbers_are_jumpers no)
		(fp_line
			(start 0.508 -0.9398)
			(end -0.508 -0.9398)
			(stroke
				(width 0.1524)
				(type default)
			)
			(layer "F.SilkS")
		)
		(fp_line
			(start -0.508 -0.9398)
			(end -0.508 0.9398)
			(stroke
				(width 0.1524)
				(type default)
			)
			(layer "F.SilkS")
		)
		(fp_rect
			(start -0.508 0.9398)
			(end 0.508 -0.9398)
			(stroke
				(width 0)
				(type default)
			)
			(fill no)
			(layer "F.CrtYd")
		)
		(fp_rect
			(start -0.508 0.9398)
			(end 0.508 -0.9398)
			(stroke
				(width 0)
				(type default)
			)
			(fill no)
			(layer "F.Fab")
		)
		(pad "1" smd custom
			(at 0 -0.4445 90)
			(size 0.1397 0.1397)
			(layers "F.Cu" "F.Mask" "F.Paste")
			(net "I2C_B_SDA_DAMP_A")
			(options
				(clearance outline)
				(anchor circle)
			)
			(primitives
				(gr_poly
					(pts
						(arc
							(start -0.1778 -0.2794)
							(mid -0.249642 -0.249642)
							(end -0.2794 -0.1778)
						)
						(arc
							(start -0.2794 0.1778)
							(mid -0.249642 0.249642)
							(end -0.1778 0.2794)
						)
						(arc
							(start 0.1778 0.2794)
							(mid 0.249642 0.249642)
							(end 0.2794 0.1778)
						)
						(arc
							(start 0.2794 -0.1778)
							(mid 0.249642 -0.249642)
							(end 0.1778 -0.2794)
						)
					)
					(width 0)
					(fill yes)
				)
			)
		)
		(pad "2" smd custom
			(at 0 0.4445 90)
			(size 0.1397 0.1397)
			(layers "F.Cu" "F.Mask" "F.Paste")
			(net "I2C_B_SDA")
			(options
				(clearance outline)
				(anchor circle)
			)
			(primitives
				(gr_poly
					(pts
						(arc
							(start -0.1778 -0.2794)
							(mid -0.249642 -0.249642)
							(end -0.2794 -0.1778)
						)
						(arc
							(start -0.2794 0.1778)
							(mid -0.249642 0.249642)
							(end -0.1778 0.2794)
						)
						(arc
							(start 0.1778 0.2794)
							(mid 0.249642 0.249642)
							(end 0.2794 0.1778)
						)
						(arc
							(start 0.2794 -0.1778)
							(mid 0.249642 -0.249642)
							(end 0.1778 -0.2794)
						)
					)
					(width 0)
					(fill yes)
				)
			)
		)
	)
)
